# T6G (Grand Teton) — schematic netlist excerpt (pin names and nets, part order shuffled) for the footprints in the layout excerpt that follows; sources: Cadence DE-HDL packaged netlist, KiCad conversion of 04192023_DAF0TMB3IC0_F0TG_MB_C_brd_V02_OCP.brd

PC2342  Q_CAP  22UF 16V 20% X6S  pkg C0805  page 190 : A = SW_P3V3_AUX_FLT ; B = GND
R3327  Q_RES  0 5% CHIP  pkg 0402LF  page 233 : A = CLK_GEN2_GPU_FPGA_OE_N ; B = CLK_GEN2_GPU_FPGA_OE_R2_N
R6247  Q_RES  4.7K 1% CHIP  pkg 0402LF  page 271 : A = P3V3_AUX ; B = HSC_TYPE_ADC_ALERT

(kicad_pcb
	(version 20260206)
	(generator "pcbnew")
	(generator_version "10.0")
	(general
		(thickness 1.6)
		(legacy_teardrops no)
	)
	(paper "A4")
	(title_block
		(title "04192023_DAF0TMB3IC0_F0TG_MB_C_brd_V02_OCP.brd")
		(comment 1 "Grand Teton / footprints 1685-1687 of 8354")
	)
	(layers
		(0 "F.Cu" signal "TOP")
		(4 "In1.Cu" signal "GND")
		(6 "In2.Cu" signal "IN1")
		(8 "In3.Cu" signal "GND1")
		(10 "In4.Cu" signal "IN2")
		(12 "In5.Cu" signal "GND2")
		(14 "In6.Cu" signal "IN3")
		(16 "In7.Cu" signal "GND3")
		(18 "In8.Cu" signal "VCC")
		(20 "In9.Cu" signal "VCC1")
		(22 "In10.Cu" signal "GND4")
		(24 "In11.Cu" signal "IN4")
		(26 "In12.Cu" signal "GND5")
		(28 "In13.Cu" signal "IN5")
		(30 "In14.Cu" signal "GND6")
		(32 "In15.Cu" signal "IN6")
		(34 "In16.Cu" signal "GND7")
		(2 "B.Cu" signal "BOTTOM")
		(9 "F.Adhes" user "F.Adhesive")
		(11 "B.Adhes" user "B.Adhesive")
		(13 "F.Paste" user "Package Geometry/Pastemask Top")
		(15 "B.Paste" user "Package Geometry/Pastemask Bottom")
		(5 "F.SilkS" user "Ref Des/Silkscreen Top")
		(7 "B.SilkS" user "Ref Des/Silkscreen Bottom")
		(1 "F.Mask" user "Board Geometry/Soldermask Top")
		(3 "B.Mask" user "Board Geometry/Soldermask Bottom")
		(17 "Dwgs.User" user "User.Drawings")
		(19 "Cmts.User" user "User.Comments")
		(21 "Eco1.User" user "User.Eco1")
		(23 "Eco2.User" user "User.Eco2")
		(25 "Edge.Cuts" user "Board Geometry/Outline")
		(27 "Margin" user)
		(31 "F.CrtYd" user "Package Geometry/Place Bound Top")
		(29 "B.CrtYd" user "Package Geometry/Place Bound Bottom")
		(35 "F.Fab" user "Ref Des/Assembly Top")
		(33 "B.Fab" user "Ref Des/Assembly Bottom")
	)
	(footprint ""
		(layer "F.Cu")
		(at 429.87341 -423.60596 90)
		(property "Reference" "R6247"
			(at 0 0 90)
			(layer "F.SilkS")
			(hide yes)
			(effects
				(font
					(size 1.27 1.27)
				)
			)
		)
		(property "Value" ""
			(at 0 0 90)
			(layer "F.Fab")
			(effects
				(font
					(size 1.27 1.27)
				)
			)
		)
		(duplicate_pad_numbers_are_jumpers no)
		(fp_line
			(start 0.7874 -0.4064)
			(end 0.7874 0.4064)
			(stroke
				(width 0.1524)
				(type default)
			)
			(layer "F.SilkS")
		)
		(fp_line
			(start -0.7874 -0.4064)
			(end 0.7874 -0.4064)
			(stroke
				(width 0.1524)
				(type default)
			)
			(layer "F.SilkS")
		)
		(fp_line
			(start 0.7874 0.4064)
			(end -0.7874 0.4064)
			(stroke
				(width 0.1524)
				(type default)
			)
			(layer "F.SilkS")
		)
		(fp_line
			(start -0.7874 0.4064)
			(end -0.7874 -0.4064)
			(stroke
				(width 0.1524)
				(type default)
			)
			(layer "F.SilkS")
		)
		(fp_line
			(start -0.12065 -0.305054)
			(end -0.12065 -0.2794)
			(stroke
				(width 0.1)
				(type default)
			)
			(layer "F.Fab")
		)
		(fp_line
			(start -0.67945 -0.305054)
			(end -0.12065 -0.305054)
			(stroke
				(width 0.1)
				(type default)
			)
			(layer "F.Fab")
		)
		(fp_line
			(start 0.67945 -0.3048)
			(end 0.67945 0.3048)
			(stroke
				(width 0.1)
				(type default)
			)
			(layer "F.Fab")
		)
		(fp_line
			(start 0.12065 -0.3048)
			(end 0.67945 -0.3048)
			(stroke
				(width 0.1)
				(type default)
			)
			(layer "F.Fab")
		)
		(fp_line
			(start 0.12065 -0.2794)
			(end 0.12065 -0.3048)
			(stroke
				(width 0.1)
				(type default)
			)
			(layer "F.Fab")
		)
		(fp_line
			(start -0.12065 -0.2794)
			(end 0.12065 -0.2794)
			(stroke
				(width 0.1)
				(type default)
			)
			(layer "F.Fab")
		)
		(fp_line
			(start 0.120396 0.2794)
			(end -0.12065 0.2794)
			(stroke
				(width 0.1)
				(type default)
			)
			(layer "F.Fab")
		)
		(fp_line
			(start -0.12065 0.2794)
			(end -0.12065 0.3048)
			(stroke
				(width 0.1)
				(type default)
			)
			(layer "F.Fab")
		)
		(fp_line
			(start 0.67945 0.3048)
			(end 0.120396 0.3048)
			(stroke
				(width 0.1)
				(type default)
			)
			(layer "F.Fab")
		)
		(fp_line
			(start 0.120396 0.3048)
			(end 0.120396 0.2794)
			(stroke
				(width 0.1)
				(type default)
			)
			(layer "F.Fab")
		)
		(fp_line
			(start -0.12065 0.3048)
			(end -0.67945 0.3048)
			(stroke
				(width 0.1)
				(type default)
			)
			(layer "F.Fab")
		)
		(fp_line
			(start -0.67945 0.3048)
			(end -0.67945 -0.305054)
			(stroke
				(width 0.1)
				(type default)
			)
			(layer "F.Fab")
		)
		(pad "1" smd circle
			(at -0.40005 0 90)
			(size 0 0)
			(layers "F.Cu" "F.Mask" "F.Paste")
			(net "P3V3_AUX")
		)
		(pad "2" smd circle
			(at 0.40005 0 90)
			(size 0 0)
			(layers "F.Cu" "F.Mask" "F.Paste")
			(net "HSC_TYPE_ADC_ALERT")
		)
	)
	(footprint ""
		(layer "F.Cu")
		(at 448.051682 -53.20411 90)
		(property "Reference" "PC2342"
			(at 0 0 90)
			(layer "F.SilkS")
			(hide yes)
			(effects
				(font
					(size 1.27 1.27)
				)
			)
		)
		(property "Value" ""
			(at 0 0 90)
			(layer "F.Fab")
			(effects
				(font
					(size 1.27 1.27)
				)
			)
		)
		(duplicate_pad_numbers_are_jumpers no)
		(fp_line
			(start 1.524 -0.762)
			(end 1.524 0.762)
			(stroke
				(width 0.1524)
				(type default)
			)
			(layer "F.SilkS")
		)
		(fp_line
			(start -1.524 -0.762)
			(end 1.524 -0.762)
			(stroke
				(width 0.1524)
				(type default)
			)
			(layer "F.SilkS")
		)
		(fp_line
			(start 1.524 0.762)
			(end -1.524 0.762)
			(stroke
				(width 0.1524)
				(type default)
			)
			(layer "F.SilkS")
		)
		(fp_line
			(start -1.524 0.762)
			(end -1.524 -0.762)
			(stroke
				(width 0.1524)
				(type default)
			)
			(layer "F.SilkS")
		)
		(fp_line
			(start 1.1049 -0.724916)
			(end -1.1049 -0.724916)
			(stroke
				(width 0.1)
				(type default)
			)
			(layer "F.Fab")
		)
		(fp_line
			(start -1.1049 -0.724916)
			(end -1.1049 0.724916)
			(stroke
				(width 0.1)
				(type default)
			)
			(layer "F.Fab")
		)
		(fp_line
			(start 1.1049 0.724916)
			(end 1.1049 -0.724916)
			(stroke
				(width 0.1)
				(type default)
			)
			(layer "F.Fab")
		)
		(fp_line
			(start -1.1049 0.724916)
			(end 1.1049 0.724916)
			(stroke
				(width 0.1)
				(type default)
			)
			(layer "F.Fab")
		)
		(pad "1" smd rect
			(at -0.889 0 270)
			(size 1.016 1.27)
			(layers "F.Cu" "F.Mask" "F.Paste")
			(net "SW_P3V3_AUX_FLT")
		)
		(pad "2" smd rect
			(at 0.889 0 270)
			(size 1.016 1.27)
			(layers "F.Cu" "F.Mask" "F.Paste")
			(net "GND")
		)
	)
	(footprint ""
		(layer "F.Cu")
		(at 36.319968 -135.889238 180)
		(property "Reference" "R3327"
			(at 0 0 180)
			(layer "F.SilkS")
			(hide yes)
			(effects
				(font
					(size 1.27 1.27)
				)
			)
		)
		(property "Value" ""
			(at 0 0 180)
			(layer "F.Fab")
			(effects
				(font
					(size 1.27 1.27)
				)
			)
		)
		(duplicate_pad_numbers_are_jumpers no)
		(fp_line
			(start 0.7874 0.4064)
			(end -0.7874 0.4064)
			(stroke
				(width 0.1524)
				(type default)
			)
			(layer "F.SilkS")
		)
		(fp_line
			(start 0.7874 -0.4064)
			(end 0.7874 0.4064)
			(stroke
				(width 0.1524)
				(type default)
			)
			(layer "F.SilkS")
		)
		(fp_line
			(start -0.7874 0.4064)
			(end -0.7874 -0.4064)
			(stroke
				(width 0.1524)
				(type default)
			)
			(layer "F.SilkS")
		)
		(fp_line
			(start -0.7874 -0.4064)
			(end 0.7874 -0.4064)
			(stroke
				(width 0.1524)
				(type default)
			)
			(layer "F.SilkS")
		)
		(fp_line
			(start 0.67945 0.3048)
			(end 0.120396 0.3048)
			(stroke
				(width 0.1)
				(type default)
			)
			(layer "F.Fab")
		)
		(fp_line
			(start 0.67945 -0.3048)
			(end 0.67945 0.3048)
			(stroke
				(width 0.1)
				(type default)
			)
			(layer "F.Fab")
		)
		(fp_line
			(start 0.12065 -0.2794)
			(end 0.12065 -0.3048)
			(stroke
				(width 0.1)
				(type default)
			)
			(layer "F.Fab")
		)
		(fp_line
			(start 0.12065 -0.3048)
			(end 0.67945 -0.3048)
			(stroke
				(width 0.1)
				(type default)
			)
			(layer "F.Fab")
		)
		(fp_line
			(start 0.120396 0.3048)
			(end 0.120396 0.2794)
			(stroke
				(width 0.1)
				(type default)
			)
			(layer "F.Fab")
		)
		(fp_line
			(start 0.120396 0.2794)
			(end -0.12065 0.2794)
			(stroke
				(width 0.1)
				(type default)
			)
			(layer "F.Fab")
		)
		(fp_line
			(start -0.12065 0.3048)
			(end -0.67945 0.3048)
			(stroke
				(width 0.1)
				(type default)
			)
			(layer "F.Fab")
		)
		(fp_line
			(start -0.12065 0.2794)
			(end -0.12065 0.3048)
			(stroke
				(width 0.1)
				(type default)
			)
			(layer "F.Fab")
		)
		(fp_line
			(start -0.12065 -0.2794)
			(end 0.12065 -0.2794)
			(stroke
				(width 0.1)
				(type default)
			)
			(layer "F.Fab")
		)
		(fp_line
			(start -0.12065 -0.305054)
			(end -0.12065 -0.2794)
			(stroke
				(width 0.1)
				(type default)
			)
			(layer "F.Fab")
		)
		(fp_line
			(start -0.67945 0.3048)
			(end -0.67945 -0.305054)
			(stroke
				(width 0.1)
				(type default)
			)
			(layer "F.Fab")
		)
		(fp_line
			(start -0.67945 -0.305054)
			(end -0.12065 -0.305054)
			(stroke
				(width 0.1)
				(type default)
			)
			(layer "F.Fab")
		)
		(pad "1" smd circle
			(at -0.40005 0 180)
			(size 0 0)
			(layers "F.Cu" "F.Mask" "F.Paste")
			(net "CLK_GEN2_GPU_FPGA_OE_N")
		)
		(pad "2" smd circle
			(at 0.40005 0 180)
			(size 0 0)
			(layers "F.Cu" "F.Mask" "F.Paste")
			(net "CLK_GEN2_GPU_FPGA_OE_R2_N")
		)
	)
)
